# TIMECARD (Time Appliance Project (Time Card)) — schematic netlist excerpt (pin names and nets, part order shuffled) for the footprints in the layout excerpt that follows; sources: Cadence DE-HDL packaged netlist, KiCad conversion of R4006-B0001-02_R01.brd

C13  CAPACITOR  22UF 10V 20%  pkg SMC_0805R_H057  page 32 : \1\ = XP5R0V ; \2\ = SG
R390  RESISTOR  33OHM 1%  pkg SMC_0402R_H016  page 26 : \1\ = SMA2_LED_RED_N ; \2\ = UNNAMED_14_LED4PV14_I266_3

(kicad_pcb
	(version 20260206)
	(generator "pcbnew")
	(generator_version "10.0")
	(general
		(thickness 1.6)
		(legacy_teardrops no)
	)
	(paper "A4")
	(title_block
		(title "timecard-production-celestica-r4006 — R4006-B0001-02_R01.brd")
		(comment 1 "Time Appliance Project (Time Card) / footprints 230-231 of 1113")
	)
	(layers
		(0 "F.Cu" signal "TOP")
		(4 "In1.Cu" signal "L02_GND1")
		(6 "In2.Cu" signal "L03_SIG1")
		(8 "In3.Cu" signal "L04_GND2")
		(10 "In4.Cu" signal "L05_VCC1")
		(12 "In5.Cu" signal "L06_VCC2")
		(14 "In6.Cu" signal "L07_GND3")
		(16 "In7.Cu" signal "L08_SIG2")
		(18 "In8.Cu" signal "L09_GND4")
		(2 "B.Cu" signal "BOTTOM")
		(9 "F.Adhes" user "F.Adhesive")
		(11 "B.Adhes" user "B.Adhesive")
		(13 "F.Paste" user "Package Geometry/Pastemask Top")
		(15 "B.Paste" user "Package Geometry/Pastemask Bottom")
		(5 "F.SilkS" user "Ref Des/Silkscreen Top")
		(7 "B.SilkS" user "Ref Des/Silkscreen Bottom")
		(1 "F.Mask" user "Board Geometry/Soldermask Top")
		(3 "B.Mask" user "Board Geometry/Soldermask Bottom")
		(17 "Dwgs.User" user "User.Drawings")
		(19 "Cmts.User" user "User.Comments")
		(21 "Eco1.User" user "User.Eco1")
		(23 "Eco2.User" user "User.Eco2")
		(25 "Edge.Cuts" user "Board Geometry/Outline")
		(27 "Margin" user)
		(31 "F.CrtYd" user "Package Geometry/Place Bound Top")
		(29 "B.CrtYd" user "Package Geometry/Place Bound Bottom")
		(35 "F.Fab" user "Ref Des/Assembly Top")
		(33 "B.Fab" user "Ref Des/Assembly Bottom")
	)
	(footprint ""
		(layer "F.Cu")
		(at 56.7944 -98.0694 -90)
		(property "Reference" "C13"
			(at -0.127 -3.59537 90)
			(unlocked yes)
			(layer "F.SilkS")
			(effects
				(font
					(size 0.7874 0.5842)
					(thickness 0.1524)
				)
			)
		)
		(property "Value" "VAL*"
			(at 0.0762 3.134106 270)
			(unlocked yes)
			(layer "F.Fab")
			(hide yes)
			(effects
				(font
					(size 0.7874 0.5842)
					(thickness 0.1524)
				)
			)
		)
		(property "Device Type" "CAPACITOR-G107-0F226-CM,22UF,2A"
			(at 0.0508 2.194306 270)
			(unlocked yes)
			(layer "F.Fab")
			(hide yes)
			(effects
				(font
					(size 0.7874 0.5842)
					(thickness 0.1524)
				)
			)
		)
		(property "User Part Number" "PARTNUM*"
			(at 0.1016 5.013706 270)
			(unlocked yes)
			(layer "Cmts.User")
			(hide yes)
			(effects
				(font
					(size 0.7874 0.5842)
					(thickness 0.1524)
				)
			)
		)
		(property "Tolerance" "TOL*"
			(at 0.0762 4.048506 270)
			(unlocked yes)
			(layer "Cmts.User")
			(hide yes)
			(effects
				(font
					(size 0.7874 0.5842)
					(thickness 0.1524)
				)
			)
		)
		(duplicate_pad_numbers_are_jumpers no)
		(fp_line
			(start -1.5748 0.9398)
			(end 1.5748 0.9398)
			(stroke
				(width 0.1)
				(type default)
			)
			(layer "F.SilkS")
		)
		(fp_line
			(start 1.5748 0.9398)
			(end 1.5748 -0.9398)
			(stroke
				(width 0.1)
				(type default)
			)
			(layer "F.SilkS")
		)
		(fp_line
			(start -1.5748 -0.9398)
			(end -1.5748 0.9398)
			(stroke
				(width 0.1)
				(type default)
			)
			(layer "F.SilkS")
		)
		(fp_line
			(start 1.5748 -0.9398)
			(end -1.5748 -0.9398)
			(stroke
				(width 0.1)
				(type default)
			)
			(layer "F.SilkS")
		)
		(fp_rect
			(start -1.5748 -0.9398)
			(end 1.5748 0.9398)
			(stroke
				(width 0)
				(type default)
			)
			(fill no)
			(layer "F.CrtYd")
		)
		(fp_line
			(start -1.016 0.635)
			(end 1.016 0.635)
			(stroke
				(width 0.1)
				(type default)
			)
			(layer "F.Fab")
		)
		(fp_line
			(start 1.016 0.635)
			(end 1.016 -0.635)
			(stroke
				(width 0.1)
				(type default)
			)
			(layer "F.Fab")
		)
		(fp_line
			(start -1.016 -0.635)
			(end -1.016 0.635)
			(stroke
				(width 0.1)
				(type default)
			)
			(layer "F.Fab")
		)
		(fp_line
			(start 1.016 -0.635)
			(end -1.016 -0.635)
			(stroke
				(width 0.1)
				(type default)
			)
			(layer "F.Fab")
		)
		(pad "1" smd rect
			(at -0.8382 0 270)
			(size 0.9652 1.3716)
			(layers "F.Cu" "F.Mask" "F.Paste")
			(net "XP5R0V")
		)
		(pad "2" smd rect
			(at 0.8382 0 270)
			(size 0.9652 1.3716)
			(layers "F.Cu" "F.Mask" "F.Paste")
			(net "SG")
		)
		(zone
			(layer "F.Cu")
			(hatch none 0.5)
			(connect_pads
				(clearance 0)
			)
			(min_thickness 0.25)
			(keepout
				(tracks allowed)
				(vias not_allowed)
				(pads allowed)
				(copperpour not_allowed)
				(footprints allowed)
			)
			(placement
				(enabled no)
				(sheetname "")
			)
			(fill
				(thermal_gap 0.5)
				(thermal_bridge_width 0.5)
				(island_removal_mode 0)
			)
			(polygon
				(pts
					(xy 57.4294 -98.298) (xy 56.1594 -98.298) (xy 56.1594 -97.8408) (xy 57.4294 -97.8408)
				)
			)
		)
	)
	(footprint ""
		(layer "F.Cu")
		(at 20.32 -30.48 180)
		(property "Reference" "R390"
			(at -2.794 -0.80137 0)
			(unlocked yes)
			(layer "F.SilkS")
			(effects
				(font
					(size 0.7874 0.5842)
					(thickness 0.1524)
				)
			)
		)
		(property "Value" "VAL*"
			(at 0.02032 2.13233 180)
			(unlocked yes)
			(layer "F.Fab")
			(hide yes)
			(effects
				(font
					(size 0.7874 0.5842)
					(thickness 0.1524)
				)
			)
		)
		(property "Tolerance" "TOL*"
			(at 0.044704 3.05435 180)
			(unlocked yes)
			(layer "Cmts.User")
			(hide yes)
			(effects
				(font
					(size 0.7874 0.5842)
					(thickness 0.1524)
				)
			)
		)
		(property "User Part Number" "PARTNUM*"
			(at 0.02032 4.024884 180)
			(unlocked yes)
			(layer "Cmts.User")
			(hide yes)
			(effects
				(font
					(size 0.7874 0.5842)
					(thickness 0.1524)
				)
			)
		)
		(property "Device Type" "RESISTOR-G155-133R0-01,33OHM,1%"
			(at 0.008382 1.210564 180)
			(unlocked yes)
			(layer "F.Fab")
			(hide yes)
			(effects
				(font
					(size 0.7874 0.5842)
					(thickness 0.1524)
				)
			)
		)
		(duplicate_pad_numbers_are_jumpers no)
		(fp_line
			(start 1.143 0.5588)
			(end 1.143 -0.5588)
			(stroke
				(width 0.1)
				(type default)
			)
			(layer "F.SilkS")
		)
		(fp_line
			(start 1.143 -0.5588)
			(end -1.143 -0.5588)
			(stroke
				(width 0.1)
				(type default)
			)
			(layer "F.SilkS")
		)
		(fp_line
			(start -1.143 0.5588)
			(end 1.143 0.5588)
			(stroke
				(width 0.1)
				(type default)
			)
			(layer "F.SilkS")
		)
		(fp_line
			(start -1.143 -0.5588)
			(end -1.143 0.5588)
			(stroke
				(width 0.1)
				(type default)
			)
			(layer "F.SilkS")
		)
		(fp_rect
			(start -1.143 -0.5588)
			(end 1.143 0.5588)
			(stroke
				(width 0)
				(type default)
			)
			(fill no)
			(layer "F.CrtYd")
		)
		(fp_line
			(start 0.508 0.3048)
			(end 0.508 -0.3048)
			(stroke
				(width 0.1)
				(type default)
			)
			(layer "F.Fab")
		)
		(fp_line
			(start 0.508 -0.3048)
			(end -0.508 -0.3048)
			(stroke
				(width 0.1)
				(type default)
			)
			(layer "F.Fab")
		)
		(fp_line
			(start -0.508 0.3048)
			(end 0.508 0.3048)
			(stroke
				(width 0.1)
				(type default)
			)
			(layer "F.Fab")
		)
		(fp_line
			(start -0.508 -0.3048)
			(end -0.508 0.3048)
			(stroke
				(width 0.1)
				(type default)
			)
			(layer "F.Fab")
		)
		(pad "1" smd rect
			(at -0.5334 0 180)
			(size 0.7112 0.6096)
			(layers "F.Cu" "F.Mask" "F.Paste")
			(net "SMA2_LED_RED_N")
		)
		(pad "2" smd rect
			(at 0.5334 0 180)
			(size 0.7112 0.6096)
			(layers "F.Cu" "F.Mask" "F.Paste")
			(net "UNNAMED_14_LED4PV14_I266_3")
		)
		(zone
			(layer "F.Cu")
			(hatch none 0.5)
			(connect_pads
				(clearance 0)
			)
			(min_thickness 0.25)
			(keepout
				(tracks not_allowed)
				(vias allowed)
				(pads allowed)
				(copperpour not_allowed)
				(footprints allowed)
			)
			(placement
				(enabled no)
				(sheetname "")
			)
			(fill
				(thermal_gap 0.5)
				(thermal_bridge_width 0.5)
				(island_removal_mode 0)
			)
			(polygon
				(pts
					(xy 20.3962 -30.1752) (xy 20.3962 -30.7848) (xy 20.2438 -30.7848) (xy 20.2438 -30.1752)
				)
			)
		)
		(zone
			(layer "F.Cu")
			(hatch none 0.5)
			(connect_pads
				(clearance 0)
			)
			(min_thickness 0.25)
			(keepout
				(tracks allowed)
				(vias not_allowed)
				(pads allowed)
				(copperpour not_allowed)
				(footprints allowed)
			)
			(placement
				(enabled no)
				(sheetname "")
			)
			(fill
				(thermal_gap 0.5)
				(thermal_bridge_width 0.5)
				(island_removal_mode 0)
			)
			(polygon
				(pts
					(xy 20.3962 -30.1752) (xy 20.3962 -30.7848) (xy 20.2438 -30.7848) (xy 20.2438 -30.1752)
				)
			)
		)
	)
)
